(kicad_pcb
	(version 20260206)
	(generator "pcbnew")
	(generator_version "10.0")
	(general
		(thickness 1.6)
		(legacy_teardrops no)
	)
	(paper "A4")
	(title_block
		(title "Bryce Canyon_R.DPB_16317-1_OCP.brd")
		(comment 1 "Bryce Canyon / footprints 1867-1870 of 2099")
	)
	(layers
		(0 "F.Cu" signal "TOP")
		(4 "In1.Cu" signal "L2GND")
		(6 "In2.Cu" signal "L3")
		(8 "In3.Cu" signal "L4VCC")
		(10 "In4.Cu" signal "L5VCC")
		(12 "In5.Cu" signal "L6")
		(14 "In6.Cu" signal "L7GND")
		(2 "B.Cu" signal "BOTTOM")
		(9 "F.Adhes" user "F.Adhesive")
		(11 "B.Adhes" user "B.Adhesive")
		(13 "F.Paste" user "Package Geometry/Pastemask Top")
		(15 "B.Paste" user "Package Geometry/Pastemask Bottom")
		(5 "F.SilkS" user "Ref Des/Silkscreen Top")
		(7 "B.SilkS" user "Ref Des/Silkscreen Bottom")
		(1 "F.Mask" user "Board Geometry/Soldermask Top")
		(3 "B.Mask" user "Board Geometry/Soldermask Bottom")
		(17 "Dwgs.User" user "User.Drawings")
		(19 "Cmts.User" user "User.Comments")
		(21 "Eco1.User" user "User.Eco1")
		(23 "Eco2.User" user "User.Eco2")
		(25 "Edge.Cuts" user "Board Geometry/Outline")
		(27 "Margin" user)
		(31 "F.CrtYd" user "Package Geometry/Place Bound Top")
		(29 "B.CrtYd" user "Package Geometry/Place Bound Bottom")
		(35 "F.Fab" user "Ref Des/Assembly Top")
		(33 "B.Fab" user "Ref Des/Assembly Bottom")
	)
	(footprint ""
		(layer "F.Cu")
		(at 234.86618 -219.03436)
		(property "Reference" "R66"
			(at 0 0 0)
			(layer "F.SilkS")
			(hide yes)
			(effects
				(font
					(size 1.27 1.27)
				)
			)
		)
		(property "Value" "0R2J-2-GP"
			(at 0.064008 -3.993896 0)
			(unlocked yes)
			(layer "F.Fab")
			(hide yes)
			(effects
				(font
					(size 1.016 1.016)
					(thickness 0.1524)
				)
			)
		)
		(property "Device Type" "R402H16"
			(at 0.064008 -5.517896 0)
			(unlocked yes)
			(layer "F.Fab")
			(hide yes)
			(effects
				(font
					(size 1.016 1.016)
					(thickness 0.1524)
				)
			)
		)
		(duplicate_pad_numbers_are_jumpers no)
		(fp_line
			(start -0.508 -0.9398)
			(end -0.508 0.9398)
			(stroke
				(width 0.1524)
				(type default)
			)
			(layer "F.SilkS")
		)
		(fp_line
			(start 0.508 -0.9398)
			(end -0.508 -0.9398)
			(stroke
				(width 0.1524)
				(type default)
			)
			(layer "F.SilkS")
		)
		(fp_rect
			(start -0.508 0.9398)
			(end 0.508 -0.9398)
			(stroke
				(width 0)
				(type default)
			)
			(fill no)
			(layer "F.CrtYd")
		)
		(fp_rect
			(start -0.508 0.9398)
			(end 0.508 -0.9398)
			(stroke
				(width 0)
				(type default)
			)
			(fill no)
			(layer "F.Fab")
		)
		(pad "1" smd custom
			(at 0 -0.4445)
			(size 0.1397 0.1397)
			(layers "F.Cu" "F.Mask" "F.Paste")
			(net "IO_EXP1_SDA")
			(options
				(clearance outline)
				(anchor circle)
			)
			(primitives
				(gr_poly
					(pts
						(arc
							(start -0.1778 -0.2794)
							(mid -0.249642 -0.249642)
							(end -0.2794 -0.1778)
						)
						(arc
							(start -0.2794 0.1778)
							(mid -0.249642 0.249642)
							(end -0.1778 0.2794)
						)
						(arc
							(start 0.1778 0.2794)
							(mid 0.249642 0.249642)
							(end 0.2794 0.1778)
						)
						(arc
							(start 0.2794 -0.1778)
							(mid 0.249642 -0.249642)
							(end 0.1778 -0.2794)
						)
					)
					(width 0)
					(fill yes)
				)
			)
		)
		(pad "2" smd custom
			(at 0 0.4445)
			(size 0.1397 0.1397)
			(layers "F.Cu" "F.Mask" "F.Paste")
			(net "I2C_DRIVE_B_PWR_SDA")
			(options
				(clearance outline)
				(anchor circle)
			)
			(primitives
				(gr_poly
					(pts
						(arc
							(start -0.1778 -0.2794)
							(mid -0.249642 -0.249642)
							(end -0.2794 -0.1778)
						)
						(arc
							(start -0.2794 0.1778)
							(mid -0.249642 0.249642)
							(end -0.1778 0.2794)
						)
						(arc
							(start 0.1778 0.2794)
							(mid 0.249642 0.249642)
							(end 0.2794 0.1778)
						)
						(arc
							(start 0.2794 -0.1778)
							(mid 0.249642 -0.249642)
							(end 0.1778 -0.2794)
						)
					)
					(width 0)
					(fill yes)
				)
			)
		)
	)
	(footprint ""
		(layer "F.Cu")
		(at 481.066602 -132.437124)
		(property "Reference" "VIA48"
			(at 0 0 0)
			(layer "F.SilkS")
			(hide yes)
			(effects
				(font
					(size 1.27 1.27)
				)
			)
		)
		(property "Value" "100OHM-8L-2D36MM-L16-GP"
			(at -3.4036 -0.4572 0)
			(unlocked yes)
			(layer "F.Fab")
			(hide yes)
			(effects
				(font
					(size 1.016 1.016)
					(thickness 0.1524)
				)
			)
		)
		(property "Device Type" "VIA-PCIE-4P-427097"
			(at -3.4036 -1.9812 0)
			(unlocked yes)
			(layer "F.Fab")
			(hide yes)
			(effects
				(font
					(size 1.016 1.016)
					(thickness 0.1524)
				)
			)
		)
		(duplicate_pad_numbers_are_jumpers no)
		(fp_rect
			(start -2.1336 0.4826)
			(end 2.1336 -0.4826)
			(stroke
				(width 0)
				(type default)
			)
			(fill no)
			(layer "F.CrtYd")
		)
		(fp_rect
			(start -2.1336 0.4826)
			(end 2.1336 -0.4826)
			(stroke
				(width 0)
				(type default)
			)
			(fill no)
			(layer "F.Fab")
		)
		(pad "1" thru_hole circle
			(at -1.651 0)
			(size 0.508 0.508)
			(drill 0.254)
			(layers "*.Cu" "*.Mask")
			(remove_unused_layers no)
			(net "GND")
			(clearance 0.2286)
			(thermal_gap 0.2286)
		)
		(pad "2" thru_hole circle
			(at -0.635 0)
			(size 0.508 0.508)
			(drill 0.254)
			(layers "*.Cu" "*.Mask")
			(remove_unused_layers no)
			(net "PHY_DRV_B_TO_SCC_B_23_DP")
			(clearance 0.2286)
			(thermal_gap 0.2286)
		)
		(pad "3" thru_hole circle
			(at 0.635 0)
			(size 0.508 0.508)
			(drill 0.254)
			(layers "*.Cu" "*.Mask")
			(remove_unused_layers no)
			(net "PHY_DRV_B_TO_SCC_B_23_DN")
			(clearance 0.2286)
			(thermal_gap 0.2286)
		)
		(pad "4" thru_hole circle
			(at 1.651 0)
			(size 0.508 0.508)
			(drill 0.254)
			(layers "*.Cu" "*.Mask")
			(remove_unused_layers no)
			(net "GND")
			(clearance 0.2286)
			(thermal_gap 0.2286)
		)
	)
	(footprint ""
		(layer "F.Cu")
		(at 280.444448 -352.367342 -90)
		(property "Reference" "R1077"
			(at 0 0 270)
			(layer "F.SilkS")
			(hide yes)
			(effects
				(font
					(size 1.27 1.27)
				)
			)
		)
		(property "Value" "0R2J-2-GP"
			(at 0.064008 -3.993896 270)
			(unlocked yes)
			(layer "F.Fab")
			(hide yes)
			(effects
				(font
					(size 1.016 1.016)
					(thickness 0.1524)
				)
			)
		)
		(property "Device Type" "R402H16"
			(at 0.064008 -5.517896 270)
			(unlocked yes)
			(layer "F.Fab")
			(hide yes)
			(effects
				(font
					(size 1.016 1.016)
					(thickness 0.1524)
				)
			)
		)
		(duplicate_pad_numbers_are_jumpers no)
		(fp_line
			(start -0.508 -0.9398)
			(end -0.508 0.9398)
			(stroke
				(width 0.1524)
				(type default)
			)
			(layer "F.SilkS")
		)
		(fp_line
			(start 0.508 -0.9398)
			(end -0.508 -0.9398)
			(stroke
				(width 0.1524)
				(type default)
			)
			(layer "F.SilkS")
		)
		(fp_rect
			(start -0.508 0.9398)
			(end 0.508 -0.9398)
			(stroke
				(width 0)
				(type default)
			)
			(fill no)
			(layer "F.CrtYd")
		)
		(fp_rect
			(start -0.508 0.9398)
			(end 0.508 -0.9398)
			(stroke
				(width 0)
				(type default)
			)
			(fill no)
			(layer "F.Fab")
		)
		(pad "1" smd custom
			(at 0 -0.4445 270)
			(size 0.1397 0.1397)
			(layers "F.Cu" "F.Mask" "F.Paste")
			(net "MAX31790_B_PWM_ST0")
			(options
				(clearance outline)
				(anchor circle)
			)
			(primitives
				(gr_poly
					(pts
						(arc
							(start -0.1778 -0.2794)
							(mid -0.249642 -0.249642)
							(end -0.2794 -0.1778)
						)
						(arc
							(start -0.2794 0.1778)
							(mid -0.249642 0.249642)
							(end -0.1778 0.2794)
						)
						(arc
							(start 0.1778 0.2794)
							(mid 0.249642 0.249642)
							(end 0.2794 0.1778)
						)
						(arc
							(start 0.2794 -0.1778)
							(mid 0.249642 -0.249642)
							(end 0.1778 -0.2794)
						)
					)
					(width 0)
					(fill yes)
				)
			)
		)
		(pad "2" smd custom
			(at 0 0.4445 270)
			(size 0.1397 0.1397)
			(layers "F.Cu" "F.Mask" "F.Paste")
			(net "GND")
			(options
				(clearance outline)
				(anchor circle)
			)
			(primitives
				(gr_poly
					(pts
						(arc
							(start -0.1778 -0.2794)
							(mid -0.249642 -0.249642)
							(end -0.2794 -0.1778)
						)
						(arc
							(start -0.2794 0.1778)
							(mid -0.249642 0.249642)
							(end -0.1778 0.2794)
						)
						(arc
							(start 0.1778 0.2794)
							(mid 0.249642 0.249642)
							(end 0.2794 0.1778)
						)
						(arc
							(start 0.2794 -0.1778)
							(mid 0.249642 -0.249642)
							(end 0.1778 -0.2794)
						)
					)
					(width 0)
					(fill yes)
				)
			)
		)
	)
	(footprint ""
		(layer "F.Cu")
		(at 363.855 -151.892 180)
		(property "Reference" "C278"
			(at 0 0 180)
			(layer "F.SilkS")
			(hide yes)
			(effects
				(font
					(size 1.27 1.27)
				)
			)
		)
		(property "Value" "SC10U16V6KX-2GP"
			(at -0.0762 -5.1308 180)
			(unlocked yes)
			(layer "F.Fab")
			(hide yes)
			(effects
				(font
					(size 1.016 1.016)
					(thickness 0.1524)
				)
			)
		)
		(property "Device Type" "C1206H71"
			(at -0.127 -6.6548 180)
			(unlocked yes)
			(layer "F.Fab")
			(hide yes)
			(effects
				(font
					(size 1.016 1.016)
					(thickness 0.1524)
				)
			)
		)
		(duplicate_pad_numbers_are_jumpers no)
		(fp_line
			(start 1.016 2.2352)
			(end -1.016 2.2352)
			(stroke
				(width 0.1524)
				(type default)
			)
			(layer "F.SilkS")
		)
		(fp_line
			(start 1.016 0.8382)
			(end 1.016 2.2352)
			(stroke
				(width 0.1524)
				(type default)
			)
			(layer "F.SilkS")
		)
		(fp_line
			(start 1.016 -2.2352)
			(end 1.016 -0.8382)
			(stroke
				(width 0.1524)
				(type default)
			)
			(layer "F.SilkS")
		)
		(fp_line
			(start -1.016 2.2352)
			(end -1.016 0.8382)
			(stroke
				(width 0.1524)
				(type default)
			)
			(layer "F.SilkS")
		)
		(fp_line
			(start -1.016 -0.8382)
			(end -1.016 -2.2352)
			(stroke
				(width 0.1524)
				(type default)
			)
			(layer "F.SilkS")
		)
		(fp_line
			(start -1.016 -2.2352)
			(end 1.016 -2.2352)
			(stroke
				(width 0.1524)
				(type default)
			)
			(layer "F.SilkS")
		)
		(fp_rect
			(start -1.0922 2.3114)
			(end 1.0922 -2.3114)
			(stroke
				(width 0)
				(type default)
			)
			(fill no)
			(layer "F.CrtYd")
		)
		(fp_poly
			(pts
				(xy 1.0922 -2.3114) (xy 1.0922 2.3114) (xy -1.0922 2.3114) (xy -1.0922 -2.3114)
			)
			(stroke
				(width 0)
				(type default)
			)
			(fill no)
			(layer "F.Fab")
		)
		(pad "1" smd rect
			(at 0 -1.397 180)
			(size 1.651 1.27)
			(layers "F.Cu" "F.Mask" "F.Paste")
			(net "P5V_HDD19")
		)
		(pad "2" smd rect
			(at 0 1.397 180)
			(size 1.651 1.27)
			(layers "F.Cu" "F.Mask" "F.Paste")
			(net "GND")
		)
	)
)
